# SCM (Grand Teton) — schematic parts with pin connectivity, parts 1165–1325 of 1428; source: Cadence DE-HDL packaged netlist (pstxprt.dat, pstxnet.dat, pstchip.dat)

R694  Q_RES  100 1% CHIP  pkg 0402LF  page 29 : 1 = USB3_MUX_PD ; 2 = GND
R695  Q_RES  0 5% CHIP  pkg 0402LF  page 47 : 1 = LED_POSTCODE_4 ; 2 = LED_POSTCODE_4_R1
R696  Q_RES  0 5% CHIP  pkg 0402LF  page 47 : 1 = LED_POSTCODE_3 ; 2 = LED_POSTCODE_3_R1
R697  Q_RES  0 5% CHIP  pkg 0402LF  page 47 : 1 = LED_POSTCODE_2 ; 2 = LED_POSTCODE_2_R1
R698  Q_RES  0 5% CHIP  pkg 0402LF  page 47 : 1 = LED_POSTCODE_1 ; 2 = LED_POSTCODE_1_R1
R699  Q_RES  4.7K 1% EMPTY  pkg 0402LF  page 27 : 1 = P3V3_AUX ; 2 = SPI_BMC_BOOT_CLK
R700  Q_RES  0 5% CHIP  pkg 0402LF  page 47 : 1 = LED_POSTCODE_0 ; 2 = LED_POSTCODE_0_R1
R701  Q_RES  0 5% CHIP  pkg 0402LF  page 28 : 1 = PWRGD_SYS_PWROK ; 2 = PWRGD_SYS_PWROK_R1
R702  Q_RES  0 5% CHIP  pkg 0402LF  page 28 : 1 = RST_PLTRST_N ; 2 = RST_PLTRST_R2_N
R703  Q_RES  0 5% CHIP  pkg 0402LF  page 28 : 1 = PWRGD_DSW_PWROK ; 2 = PWRGD_DSW_PWROK_R3
R705  Q_RES  33.2 1% CHIP  pkg 0402LF  page 12 : 1 = FM_BMC_DBP_PRESENT_N ; 2 = FM_BMC_DBP_PRESENT_R_N
R706  Q_RES  4.7K 1% CHIP  pkg 0402LF  page 12 : 1 = P3V3_AUX ; 2 = FM_BMC_DBP_PRESENT_N
R707  Q_RES  0 5% CHIP  pkg 0402LF  page 29 : 1 = FM_DEBUG_PORT_R_PRSNT_N ; 2 = FM_DEBUG_PORT_PRSNT_N
R708  Q_RES  0 5% CHIP  pkg 0402LF  page 55 : 1 = EN_P1V2_AUX ; 2 = EN_P1V2_AUX_R
R709  Q_RES  2.2K 5% CHIP  pkg 0402LF  page 52 : 1 = P3V3_RGM ; 2 = PWRGD_P3V3_RGM_R
R710  Q_RES  100K 1% CHIP  pkg 0402LF  page 22 : 1 = P3V3_AUX ; 2 = U43_CT
R711  Q_RES  0 5% EMPTY  pkg 0402LF  page 22 : 1 = PWRGD_PSU_AC_PWROK ; 2 = PWRGD_P1V0_AUX_DELAY
R712  Q_RES  10K 1% EMPTY  pkg 0402LF  page 29 : 1 = P3V3_AUX ; 2 = USB3_MUX_PD
R713  Q_RES  33.2 1% CHIP  pkg 0402LF  page 17 : 1 = LPC_ESPI_SEL_R ; 2 = LPC_ESPI_SEL
R714  Q_RES  2K 1% CHIP  pkg 0402LF  page 27 : 1 = LPC_ESPI_SEL ; 2 = LPC_ESPI_SEL_R1
R715  Q_RES  33.2 1% CHIP  pkg 0402LF  page 30 : 1 = UART_BMC_5_TXD_BUF1 ; 2 = UART_BMC_5_TXD_BUF1_R
R716  Q_RES  10K 1% CHIP  pkg 0402LF  page 17 : 1 = P5V_AUX ; 2 = LPC_ESPI_SEL_N
R717  Q_RES  4.7K 1% CHIP  pkg 0402LF  page 15 : 1 = P3V3_AUX ; 2 = RST_BMC_RSTBTN_OUT_N
R718  Q_RES  33.2 1% CHIP  pkg 0402LF  page 34 : 1 = RST_PLTRST_N ; 2 = RST_PLTRST_R1_N
R719  Q_RES  0 5% EMPTY  pkg 0402LF  page 28 : 1 = PWRGD_PSU_AC_PWROK ; 2 = PWRGD_DSW_PWROK_R3
R720  Q_RES  0 5% CHIP  pkg 0402LF  page 28 : 1 = FM_CPU_MSMI_CATERR_LVT3_N ; 2 = FM_CPU_MSMI_CATERR_LVT3_R3_N
R721  Q_RES  0 5% CHIP  pkg 0402LF  page 28 : 1 = FM_SLPS3_GF_N ; 2 = FM_SLPS3_GF_R2_N
R722  Q_RES  0 5% CHIP  pkg 0402LF  page 13 : 1 = FM_SLPS3_GF_R1_N ; 2 = FM_SLPS3_GF_N
R724  Q_RES  33.2 1% CHIP  pkg 0402LF  page 44 : 1 = SPI_BMC_BIOS_ROM_IO2 ; 2 = SPI_BMC_BIOS_ROM_R_IO2
R725  Q_RES  33.2 1% CHIP  pkg 0402LF  page 44 : 1 = SPI_BMC_BIOS_ROM_IO3 ; 2 = SPI_BMC_BIOS_ROM_R_IO3
R726  Q_RES  0 5% CHIP  pkg 0402LF  page 30 : 1 = SPA_SIN_SW_BUF_R ; 2 = SPA_SIN_SW_BUF
R728  Q_RES  0 5% CHIP  pkg 0402LF  page 44 : 1 = SPI_BMC_BIOS_CS0_N ; 2 = SPI_BMC_BIOS_SOURCE_CS0_N
R730  Q_RES  4.7K 1% CHIP  pkg 0402LF  page 29 : 1 = P3V3_AUX ; 2 = FM_DEBUG_PORT_R_PRSNT_N
R731  Q_RES  0 5% CHIP  pkg 0402LF  page 29 : 1 = SMB_DEBUG_AUX_LVC3_USB_SDA ; 2 = SMB_DEBUG_AUX_LVC3_USB_R2_SDA
R732  Q_RES  0 5% CHIP  pkg 0402LF  page 29 : 1 = SMB_DEBUG_AUX_LVC3_USB_SCL ; 2 = SMB_DEBUG_AUX_LVC3_USB_R2_SCL
R733  Q_RES  0 5% CHIP  pkg 0402LF  page 50 : 1 = REAR_ID_RST_BTN_N ; 2 = FM_DEBUG_RST_BTN_N
R734  Q_RES  0 5% CHIP  pkg 0402LF  page 50 : 1 = REAR_PWR_BTN_N ; 2 = FM_DEBUG_PWR_BTN_N
R735  Q_RES  1K 1% CHIP  pkg 0402LF  page 28 : 1 = P3V3_AUX ; 2 = FM_UART_SWITCH_N
R736  Q_RES  1K 1% CHIP  pkg 0402LF  page 28 : 1 = P3V3_AUX ; 2 = FM_SOL_UART_CH_SEL_R3
R737  Q_RES  4.7K 1% EMPTY  pkg 0402LF  page 30 : 1 = P3V3_AUX ; 2 = SPA_SIN_SW_BUF
R738  Q_RES  4.7K 1% CHIP  pkg 0402LF  page 28 : 1 = P3V3_AUX ; 2 = LED_POSTCODE_A0
R739  Q_RES  4.7K 1% CHIP  pkg 0402LF  page 28 : 1 = P3V3_AUX ; 2 = LED_POSTCODE_A1
R740  Q_RES  4.7K 1% CHIP  pkg 0402LF  page 28 : 1 = P3V3_AUX ; 2 = LED_POSTCODE_A2
R741  Q_RES  4.7K 1% CHIP  pkg 0402LF  page 30 : 1 = P3V3_AUX ; 2 = UART_BMC_5_RXD_BUF
R742  Q_RES  4.7K 1% EMPTY  pkg 0402LF  page 30 : 1 = P3V3_AUX ; 2 = SPA_SOUT_SW_BUF
R743  Q_RES  100 1% EMPTY  pkg 0402LF  page 28 : 1 = LED_POSTCODE_A0 ; 2 = GND
R744  Q_RES  100 1% EMPTY  pkg 0402LF  page 28 : 1 = LED_POSTCODE_A1 ; 2 = GND
R745  Q_RES  100 1% EMPTY  pkg 0402LF  page 28 : 1 = LED_POSTCODE_A2 ; 2 = GND
R746  Q_RES  0 5% CHIP  pkg 0402LF  page 36 : 1 = IRQ_PCH_TPM_SPI_N ; 2 = IRQ_PCH_TPM_SPI_R2_N
R747  Q_RES  0 5% CHIP  pkg 0402LF  page 36 : 1 = FM_BMC_CRASHLOG_TRIG_N ; 2 = FM_BMC_CRASHLOG_TRIG_R2_N
R748  Q_RES  0 5% CHIP  pkg 0402LF  page 36 : 1 = PU_FPGA_NCONFIG ; 2 = RST_ROT_CPU_N
R749  Q_RES  4.7K 1% CHIP  pkg 0402LF  page 42 : 1 = P3V3_AUX ; 2 = FM_BMC_CRASHLOG_TRIG_N
R750  Q_RES  33.2 1% CHIP  pkg 0402LF  page 36 : 1 = FM_BMC_DEBUG_SW_N ; 2 = FM_BMC_DEBUG_SW_R2_N
R751  Q_RES  2K 1% CHIP  pkg 0402LF  page 22 : 1 = P3V3_AUX ; 2 = PWRGD_P1V0_AUX_DELAY_R1
R752  Q_RES  33.2 1% CHIP  pkg 0402LF  page 25 : 1 = RST_SPI_FLASH_N ; 2 = RST_SPI_FLASH_R_N
R753  Q_RES  4.7K 1% EMPTY  pkg 0402LF  page 27 : 1 = P3V3_AUX ; 2 = SPI_BMC_BOOT_MISO
R754  Q_RES  4.7K 1% EMPTY  pkg 0402LF  page 27 : 1 = P3V3_RGM ; 2 = UART_BMC_5_TXD_R
R757  Q_RES  33.2 1% CHIP  pkg 0402LF  page 30 : 1 = UART_BMC_5_RXD_BUF1_R ; 2 = UART_BMC_5_RXD_R
R758  Q_RES  4.7K 1% CHIP  pkg 0402LF  page 30 : 1 = P3V3_RGM ; 2 = UART_BMC_5_RXD_R
R759  Q_RES  33.2 1% CHIP  pkg 0402LF  page 13 : 1 = UART_BMC_5_RXD ; 2 = UART_BMC_5_RXD_R
R760  Q_RES  33.2 1% CHIP  pkg 0402LF  page 13 : 1 = FM_BMC_CRASHLOG_TRIG_N ; 2 = FM_BMC_CRASHLOG_TRIG_R1_N
R761  Q_RES  33.2 1% CHIP  pkg 0402LF  page 12 : 1 = UART_6_BMC_TXD ; 2 = UART_6_BMC_R_TXD
R762  Q_RES  33.2 1% CHIP  pkg 0402LF  page 12 : 1 = UART_6_BMC_RXD ; 2 = UART_6_BMC_R_RXD
R763  Q_RES  33.2 1% CHIP  pkg 0402LF  page 13 : 1 = FM_PCH_BMC_THERMTRIP_N ; 2 = FM_PLT_BMC_THERMTRIP_N_R
R764  Q_RES  0 5% EMPTY  pkg 0402LF  page 55 : 1 = PWRGD_P1V8_AUX ; 2 = EN_P1V2_AUX_R
R765  Q_RES  4.7K 1% CHIP  pkg 0402LF  page 30 : 1 = P3V3_AUX ; 2 = UART_BMC_5_TXD_BUF_R
R766  Q_RES  33.2 1% CHIP  pkg 0402LF  page 30 : 1 = UART_BMC_5_RXD_BUF1 ; 2 = UART_BMC_5_RXD_BUF1_SW
R767  Q_RES  33.2 1% CHIP  pkg 0402LF  page 34 : 1 = FM_TPM_PRSNT_0_N ; 2 = FM_TPM_PRSNT_0_R_N
R768  Q_RES  8.2K 5% CHIP  pkg 0402LF  page 50 : 1 = P3V3_AUX ; 2 = REAR_PWR_BTN_N
R769  Q_RES  33.2 1% CHIP  pkg 0402LF  page 35 : 1 = FM_THROTTLE_N ; 2 = FM_THROTTLE_R_N
R770  Q_RES  4.7K 1% EMPTY  pkg 0402LF  page 27 : 1 = GND ; 2 = UART_BMC_5_TXD_R
R773  Q_RES  33.2 1% CHIP  pkg 0402LF  page 35 : 1 = FM_SLPS3_GF_N ; 2 = FM_SLPS3_GF_R_N
R774  Q_RES  4.7K 1% CHIP  pkg 0402LF  page 13 : 1 = P3V3_AUX ; 2 = FM_SLPS3_GF_N
R775  Q_RES  1K 1% CHIP  pkg 0402LF  page 15 : 1 = BATTERY_DETECT ; 2 = BATTERY_DETECT_R
R776  Q_RES  47K 1% CHIP  pkg 0402LF  page 15 : 1 = BATTERY_DETECT_R ; 2 = GND
R777  Q_RES  200K 1% CHIP  pkg 0402LF  page 15 : 1 = P3V_BAT_R ; 2 = P3V_BAT_R1
R778  Q_RES  100K 1% CHIP  pkg 0402LF  page 15 : 1 = P3V_BAT_SENSOR ; 2 = GND
R779  Q_RES  0 5% CHIP  pkg 0402LF  page 17 : 1 = P2V5_AUX ; 2 = ADCVREFEXT1
R780  Q_RES  0 5% EMPTY  pkg 0402LF  page 17 : 1 = P2V5_AUX ; 2 = ADCVREFEXT0
R781  Q_RES  0 5% EMPTY  pkg 0402LF  page 17 : 1 = P1V8_AUX ; 2 = ADCVREFEXT1
R782  Q_RES  0 5% EMPTY  pkg 0402LF  page 17 : 1 = P1V2_AUX ; 2 = ADCVREFEXT1
R783  Q_RES  0 5% CHIP  pkg 0402LF  page 17 : 1 = P1V8_AUX ; 2 = ADCVREFEXT0
R784  Q_RES  0 5% EMPTY  pkg 0402LF  page 17 : 1 = P1V2_AUX ; 2 = ADCVREFEXT0
R785  Q_RES  15.8K 1% CHIP  pkg 0402LF  page 15 : 1 = P12V_AUX ; 2 = P12V_SENSOR
R786  Q_RES  2K 1% CHIP  pkg 0402LF  page 15 : 1 = P12V_SENSOR ; 2 = GND
R787  Q_RES  5.36K 1% CHIP  pkg 0402LF  page 15 : 1 = P5V_AUX ; 2 = P5V_SENSOR
R788  Q_RES  2K 1% CHIP  pkg 0402LF  page 15 : 1 = P5V_SENSOR ; 2 = GND
R789  Q_RES  2.87K 1% CHIP  pkg 0402LF  page 15 : 1 = P3V3_AUX ; 2 = P3V3_SENSOR
R790  Q_RES  2K 1% CHIP  pkg 0402LF  page 15 : 1 = P3V3_SENSOR ; 2 = GND
R791  Q_RES  1.69K 1% CHIP  pkg 0402LF  page 15 : 1 = P2V5_AUX ; 2 = P2V5_SENSOR
R792  Q_RES  2K 1% CHIP  pkg 0402LF  page 15 : 1 = P2V5_SENSOR ; 2 = GND
R793  Q_RES  665 1% CHIP  pkg 0402LF  page 15 : 1 = P1V8_AUX ; 2 = P1V8_SENSOR
R794  Q_RES  2K 1% CHIP  pkg 0402LF  page 15 : 1 = P1V8_SENSOR ; 2 = GND
R795  Q_RES  1K 1% CHIP  pkg 0402LF  page 15 : 1 = P1V2_AUX ; 2 = P1V2_SENSOR
R796  Q_RES  1K 1% CHIP  pkg 0402LF  page 15 : 1 = P1V0_AUX ; 2 = P1V0_SENSOR
R797  Q_RES  2.87K 1% CHIP  pkg 0402LF  page 15 : 1 = PGPPA_BMC_AUX ; 2 = PGPPA_BMC_AUX_SENSOR
R798  Q_RES  2K 1% CHIP  pkg 0402LF  page 15 : 1 = PGPPA_BMC_AUX_SENSOR ; 2 = GND
R799  Q_RES  33.2 1% CHIP  pkg 0402LF  page 13 : 1 = SPI_BMC_BIOS_CS0_N ; 2 = SPI_BMC_BIOS_CS0_R1_N
R801  Q_RES  33.2 1% CHIP  pkg 0402LF  page 13 : 1 = SPI_BMC_BOOT_CS0_R_N ; 2 = SPI_BMC_BOOT_CS0_R1_N
R802  Q_RES  33.2 1% CHIP  pkg 0402LF  page 13 : 1 = SPI_BMC_BOOT_CS1_R_N ; 2 = SPI_BMC_BOOT_CS1_R1_N
R804  Q_RES  0 5% CHIP  pkg 0402LF  page 15 : 1 = SYS_BMC_PWRBTN_R1_N ; 2 = SYS_BMC_PWRBTN_R_N
R805  Q_RES  4.7K 1% CHIP  pkg 0402LF  page 13 : 1 = P3V3_AUX ; 2 = BMC_HEARTBEAT_N
R806  Q_RES  4.7K 1% CHIP  pkg 0402LF  page 34 : 1 = P3V3_AUX ; 2 = PU_25M_FPGA_CLK_EN
R807  Q_RES  33.2 1% CHIP  pkg 0402LF  page 34 : 1 = CLK_25M_OSC_FPGA_R ; 2 = CLK_25M_OSC_FPGA
R808  Q_RES  10K 1% CHIP  pkg 0402LF  page 34 : 1 = PU_FPGA_CONFIG_DONE ; 2 = PVCCIO_AUX_PLD
R809  Q_RES  10K 1% CHIP  pkg 0402LF  page 34 : 1 = PU_FPGA_NCONFIG ; 2 = PVCCIO_AUX_PLD
R810  Q_RES  10K 1% CHIP  pkg 0402LF  page 34 : 1 = PU_FPGA_NSTATUS ; 2 = PVCCIO_AUX_PLD
R811  Q_RES  0 5% EMPTY  pkg 0402LF  page 10 : 1 = PCH_BEEP_LED ; 2 = PCH_BEEP_R_LED
R812  Q_RES  33.2 1% CHIP  pkg 0402LF  page 49 : 1 = PWR_LED_BUF_N ; 2 = PWR_LED_BUF_N_R
R813  Q_RES  33.2 1% CHIP  pkg 0402LF  page 49 : 1 = HDD_LED_BUF ; 2 = HDD_LED_BUF_R
R814  Q_RES  10K 1% CHIP  pkg 0402LF  page 49 : 1 = P5V_AUX ; 2 = PWR_LED_BUF_N_R
R815  Q_RES  10K 1% CHIP  pkg 0402LF  page 49 : 1 = P5V_AUX ; 2 = HDD_LED_BUF_R
R816  Q_RES  4.7K 1% CHIP  pkg 0402LF  page 13 : 1 = P3V3_AUX ; 2 = IRQ_PCH_SCI_WHEA_N
R817  Q_RES  100K 1% EMPTY  pkg 0402LF  page 12 : 1 = SMB_BMC_MM13_R_SCL ; 2 = GND
R818  Q_RES  100K 1% EMPTY  pkg 0402LF  page 12 : 1 = SMB_BMC_MM13_R_SDA ; 2 = GND
R819  Q_RES  100K 1% EMPTY  pkg 0402LF  page 12 : 1 = SMB_BMC_MM14_R_SCL ; 2 = GND
R820  Q_RES  100K 1% EMPTY  pkg 0402LF  page 12 : 1 = SMB_BMC_MM14_R_SDA ; 2 = GND
R821  Q_RES  4.7K 1% EMPTY  pkg 0402LF  page 13 : 1 = P3V3_AUX ; 2 = FM_BMC_ONCTL_R_N
R822  Q_RES  0 5% CHIP  pkg 0402LF  page 10 : 1 = FM_PRSNT_1_N ; 2 = FM_PRSNT_0_R_N
R823  Q_RES  100K 1% CHIP  pkg 0402LF  page 11 : 1 = GND ; 2 = FM_VIRTUAL_RESEAT
R824  Q_RES  33.2 1% CHIP  pkg 0402LF  page 13 : 1 = FM_VIRTUAL_RESEAT ; 2 = FM_VIRTUAL_RESEAT_BMC
R825  Q_RES  33.2 1% CHIP  pkg 0402LF  page 35 : 1 = RST_ROT_CPU_N ; 2 = RST_ROT_CPU_R_N
R826  Q_RES  33.2 1% CHIP  pkg 0402LF  page 13 : 1 = IRQ_PCH_SCI_WHEA_R_N ; 2 = IRQ_PCH_SCI_WHEA_N
R827  Q_RES  33.2 1% CHIP  pkg 0402LF  page 25 : 1 = RST_SPI_FLASH_BUF_R3_N ; 2 = RST_SPI_FLASH_BUF_N
R828  Q_RES  4.7K 1% EMPTY  pkg 0402LF  page 11 : 1 = P3V3_AUX ; 2 = RST_ROT_CPU_N
R829  Q_RES  25.5K 1% CHIP  pkg 0402LF  page 53 : 1 = P2V5_AUX ; 2 = U39_ADJ
R830  Q_RES  12K 1% CHIP  pkg 0402LF  page 53 : 1 = U39_ADJ ; 2 = GND
R831  Q_RES  15K 1% CHIP  pkg 0402LF  page 54 : 1 = P1V8_AUX ; 2 = U41_ADJ
R832  Q_RES  12K 1% CHIP  pkg 0402LF  page 54 : 1 = U41_ADJ ; 2 = GND
R833  Q_RES  33.2 1% CHIP  pkg 0402LF  page 35 : 1 = FM_ESPI_PLD_EN ; 2 = FM_ESPI_PLD_R_EN
R834  Q_RES  10K 1% EMPTY  pkg 0402LF  page 32 : 1 = P3V3_RGM ; 2 = JTAG_SCM_TCK
R835  Q_RES  4.7K 1% CHIP  pkg 0402LF  page 42 : 1 = P3V3_AUX ; 2 = FM_ADR_TRIGGER_N
R836  Q_RES  33.2 1% CHIP  pkg 0402LF  page 13 : 1 = PWRGD_PSU_AC_PWROK ; 2 = PWRGD_PSU_AC_PWROK_BMC
R837  Q_RES  33.2 1% CHIP  pkg 0402LF  page 34 : 1 = PWRGD_PSU_AC_PWROK ; 2 = PWRGD_PSU_AC_PWROK_PLD
R838  Q_RES  0 5% CHIP  pkg 0402LF  page 10 : 1 = HDD_LED_N ; 2 = FM_HDD_LED_N
R839  Q_RES  8.2K 5% CHIP  pkg 0402LF  page 49 : 1 = PWR_LED ; 2 = GND
R840  Q_RES  33.2 1% CHIP  pkg 0402LF  page 13 : 1 = PWRGD_SYS_PWROK ; 2 = PWRGD_SYS_PWROK_BMC
R841  Q_RES  33.2 1% CHIP  pkg 0402LF  page 35 : 1 = PWRGD_SYS_PWROK_PLD ; 2 = PWRGD_SYS_PWROK
R842  Q_RES  4.7K 1% CHIP  pkg 0402LF  page 27 : 1 = P3V3_AUX ; 2 = SMB_BMC_ALERT9_N
R843  Q_RES  4.7K 1% CHIP  pkg 0402LF  page 27 : 1 = P3V3_AUX ; 2 = SMB_BMC_ALERT10_N
R844  Q_RES  4.7K 1% CHIP  pkg 0402LF  page 27 : 1 = P3V3_AUX ; 2 = SMB_BMC_ALERT12_N
R846  Q_RES  4.7K 1% EMPTY  pkg 0402LF  page 27 : 1 = P3V3_AUX ; 2 = FM_BMC_EN_DET_R
R847  Q_RES  0 5% CHIP  pkg 0402LF  page 10 : 1 = PCH_BEEP_LED ; 2 = FM_PCH_BEEP_LED
R848  Q_RES  4.7K 1% CHIP  pkg 0402LF  page 27 : 1 = P3V3_AUX ; 2 = SMB_BMC_ALERT16_N
R849  Q_RES  33.2 1% CHIP  pkg 0402LF  page 21 : 1 = SMB_BMC_MM16_R5_SCL ; 2 = SMB_BMC_MM16_R1_SCL
R850  Q_RES  33.2 1% CHIP  pkg 0402LF  page 21 : 1 = SMB_BMC_MM16_R5_SDA ; 2 = SMB_BMC_MM16_R1_SDA
R851  Q_RES  4.7K 1% CHIP  pkg 0402LF  page 27 : 1 = P3V3_AUX ; 2 = SMB_BMC_ALERT15_N
R852  Q_RES  68.1 1% CHIP  pkg 0402LF  page 44 : 1 = FM_BMC_MUX_CS_SPI_SEL_0 ; 2 = FM_BMC_BIOS_MUX_CS_SPI_R_SEL_0
R853  Q_RES  0 5% CHIP  pkg 0402LF  page 15 : 1 = FM_INTRUDER_R_N ; 2 = FM_INTRUDER_N
R854  Q_RES  4.7K 1% EMPTY  pkg 0402LF  page 14 : 1 = P1V8_AUX ; 2 = FM_BOARD_BMC_REV_ID2
R855  Q_RES  1K 1% CHIP  pkg 0402LF  page 14 : 1 = FM_BOARD_BMC_REV_ID2 ; 2 = GND
R856  Q_RES  4.7K 1% CHIP  pkg 0402LF  page 14 : 1 = P1V8_AUX ; 2 = FM_BOARD_BMC_REV_ID1
R857  Q_RES  1K 1% EMPTY  pkg 0402LF  page 14 : 1 = FM_BOARD_BMC_REV_ID1 ; 2 = GND
R858  Q_RES  4.7K 1% CHIP  pkg 0402LF  page 14 : 1 = P1V8_AUX ; 2 = FM_BOARD_BMC_REV_ID0
R859  Q_RES  33.2 1% CHIP  pkg 0402LF  page 44 : 1 = SPI_SYS_R_CLK ; 2 = SPI_SYS_MUX_CLK
R860  Q_RES  22 1% CHIP  pkg 0402LF  page 44 : 1 = SPI_SYS_R_MOSI ; 2 = SPI_SYS_MUX_MOSI
R861  Q_RES  22 1% CHIP  pkg 0402LF  page 44 : 1 = SPI_SYS_R_MISO ; 2 = SPI_SYS_MUX_MISO
R862  Q_RES  22 1% CHIP  pkg 0402LF  page 44 : 1 = SPI_SYS_WP_R_IO2 ; 2 = SPI_SYS_MUX_WP_IO2
R863  Q_RES  22 1% CHIP  pkg 0402LF  page 44 : 1 = SPI_SYS_HOLD_R_IO3 ; 2 = SPI_SYS_MUX_HOLD_IO3
R864  Q_RES  33.2 1% CHIP  pkg 0402LF  page 44 : 1 = SPI_SYS_CS0_N ; 2 = SPI_PCH_SECURE_CS0_N
R865  Q_RES  1K 1% EMPTY  pkg 0402LF  page 14 : 1 = FM_BOARD_BMC_REV_ID0 ; 2 = GND
